(kicad_pcb
	(version 20260206)
	(generator "pcbnew")
	(generator_version "10.0")
	(general
		(thickness 1.6)
		(legacy_teardrops no)
	)
	(paper "A4")
	(title_block
		(title "12092022_DA0F0TYB4D0_F0T_Panel_BD_Front_D_brd_v02_OCP.brd")
		(comment 1 "Grand Teton / footprints 3-9 of 128")
	)
	(layers
		(0 "F.Cu" signal "TOP")
		(4 "In1.Cu" signal "GND")
		(6 "In2.Cu" signal "GND1")
		(2 "B.Cu" signal "BOTTOM")
		(9 "F.Adhes" user "F.Adhesive")
		(11 "B.Adhes" user "B.Adhesive")
		(13 "F.Paste" user "Package Geometry/Pastemask Top")
		(15 "B.Paste" user "Package Geometry/Pastemask Bottom")
		(5 "F.SilkS" user "Ref Des/Silkscreen Top")
		(7 "B.SilkS" user "Ref Des/Silkscreen Bottom")
		(1 "F.Mask" user "Board Geometry/Soldermask Top")
		(3 "B.Mask" user "Board Geometry/Soldermask Bottom")
		(17 "Dwgs.User" user "User.Drawings")
		(19 "Cmts.User" user "User.Comments")
		(21 "Eco1.User" user "User.Eco1")
		(23 "Eco2.User" user "User.Eco2")
		(25 "Edge.Cuts" user "Board Geometry/Outline")
		(27 "Margin" user)
		(31 "F.CrtYd" user "Package Geometry/Place Bound Top")
		(29 "B.CrtYd" user "Package Geometry/Place Bound Bottom")
		(35 "F.Fab" user "Ref Des/Assembly Top")
		(33 "B.Fab" user "Ref Des/Assembly Bottom")
	)
	(footprint ""
		(layer "F.Cu")
		(at 1.397 -32.385)
		(property "Reference" "ME1"
			(at 0 0 0)
			(layer "F.SilkS")
			(hide yes)
			(effects
				(font
					(size 1.27 1.27)
				)
			)
		)
		(property "Value" ""
			(at 0 0 0)
			(layer "F.Fab")
			(effects
				(font
					(size 1.27 1.27)
				)
			)
		)
		(duplicate_pad_numbers_are_jumpers no)
	)
	(footprint ""
		(layer "F.Cu")
		(at 9.525 -26.289 180)
		(property "Reference" "R6"
			(at 1.651 0.35433 0)
			(unlocked yes)
			(layer "F.SilkS")
			(effects
				(font
					(size 0.7874 0.5842)
					(thickness 0.1524)
				)
			)
		)
		(property "Value" ""
			(at 0 0 180)
			(layer "F.Fab")
			(effects
				(font
					(size 1.27 1.27)
				)
			)
		)
		(duplicate_pad_numbers_are_jumpers no)
		(fp_line
			(start 0.7874 0.4064)
			(end -0.7874 0.4064)
			(stroke
				(width 0.1524)
				(type default)
			)
			(layer "F.SilkS")
		)
		(fp_line
			(start 0.7874 -0.4064)
			(end 0.7874 0.4064)
			(stroke
				(width 0.1524)
				(type default)
			)
			(layer "F.SilkS")
		)
		(fp_line
			(start -0.7874 0.4064)
			(end -0.7874 -0.4064)
			(stroke
				(width 0.1524)
				(type default)
			)
			(layer "F.SilkS")
		)
		(fp_line
			(start -0.7874 -0.4064)
			(end 0.7874 -0.4064)
			(stroke
				(width 0.1524)
				(type default)
			)
			(layer "F.SilkS")
		)
		(fp_line
			(start 0.67945 0.3048)
			(end 0.120396 0.3048)
			(stroke
				(width 0.1)
				(type default)
			)
			(layer "F.Fab")
		)
		(fp_line
			(start 0.67945 -0.3048)
			(end 0.67945 0.3048)
			(stroke
				(width 0.1)
				(type default)
			)
			(layer "F.Fab")
		)
		(fp_line
			(start 0.12065 -0.2794)
			(end 0.12065 -0.3048)
			(stroke
				(width 0.1)
				(type default)
			)
			(layer "F.Fab")
		)
		(fp_line
			(start 0.12065 -0.3048)
			(end 0.67945 -0.3048)
			(stroke
				(width 0.1)
				(type default)
			)
			(layer "F.Fab")
		)
		(fp_line
			(start 0.120396 0.3048)
			(end 0.120396 0.2794)
			(stroke
				(width 0.1)
				(type default)
			)
			(layer "F.Fab")
		)
		(fp_line
			(start 0.120396 0.2794)
			(end -0.12065 0.2794)
			(stroke
				(width 0.1)
				(type default)
			)
			(layer "F.Fab")
		)
		(fp_line
			(start -0.12065 0.3048)
			(end -0.67945 0.3048)
			(stroke
				(width 0.1)
				(type default)
			)
			(layer "F.Fab")
		)
		(fp_line
			(start -0.12065 0.2794)
			(end -0.12065 0.3048)
			(stroke
				(width 0.1)
				(type default)
			)
			(layer "F.Fab")
		)
		(fp_line
			(start -0.12065 -0.2794)
			(end 0.12065 -0.2794)
			(stroke
				(width 0.1)
				(type default)
			)
			(layer "F.Fab")
		)
		(fp_line
			(start -0.12065 -0.305054)
			(end -0.12065 -0.2794)
			(stroke
				(width 0.1)
				(type default)
			)
			(layer "F.Fab")
		)
		(fp_line
			(start -0.67945 0.3048)
			(end -0.67945 -0.305054)
			(stroke
				(width 0.1)
				(type default)
			)
			(layer "F.Fab")
		)
		(fp_line
			(start -0.67945 -0.305054)
			(end -0.12065 -0.305054)
			(stroke
				(width 0.1)
				(type default)
			)
			(layer "F.Fab")
		)
		(pad "1" smd circle
			(at -0.40005 0 180)
			(size 0 0)
			(layers "F.Cu" "F.Mask" "F.Paste")
			(net "P5V_STBY")
		)
		(pad "2" smd circle
			(at 0.40005 0 180)
			(size 0 0)
			(layers "F.Cu" "F.Mask" "F.Paste")
			(net "SYSTEM_FAULT_ID_LED_R1_N")
		)
	)
	(footprint ""
		(layer "F.Cu")
		(at 3.048 -29.083)
		(property "Reference" "R9"
			(at -0.381 -2.13233 0)
			(unlocked yes)
			(layer "F.SilkS")
			(effects
				(font
					(size 0.7874 0.5842)
					(thickness 0.1524)
				)
			)
		)
		(property "Value" ""
			(at 0 0 0)
			(layer "F.Fab")
			(effects
				(font
					(size 1.27 1.27)
				)
			)
		)
		(duplicate_pad_numbers_are_jumpers no)
		(fp_line
			(start -0.7874 -0.4064)
			(end 0.7874 -0.4064)
			(stroke
				(width 0.1524)
				(type default)
			)
			(layer "F.SilkS")
		)
		(fp_line
			(start -0.7874 0.4064)
			(end -0.7874 -0.4064)
			(stroke
				(width 0.1524)
				(type default)
			)
			(layer "F.SilkS")
		)
		(fp_line
			(start 0.7874 -0.4064)
			(end 0.7874 0.4064)
			(stroke
				(width 0.1524)
				(type default)
			)
			(layer "F.SilkS")
		)
		(fp_line
			(start 0.7874 0.4064)
			(end -0.7874 0.4064)
			(stroke
				(width 0.1524)
				(type default)
			)
			(layer "F.SilkS")
		)
		(fp_line
			(start -0.67945 -0.305054)
			(end -0.12065 -0.305054)
			(stroke
				(width 0.1)
				(type default)
			)
			(layer "F.Fab")
		)
		(fp_line
			(start -0.67945 0.3048)
			(end -0.67945 -0.305054)
			(stroke
				(width 0.1)
				(type default)
			)
			(layer "F.Fab")
		)
		(fp_line
			(start -0.12065 -0.305054)
			(end -0.12065 -0.2794)
			(stroke
				(width 0.1)
				(type default)
			)
			(layer "F.Fab")
		)
		(fp_line
			(start -0.12065 -0.2794)
			(end 0.12065 -0.2794)
			(stroke
				(width 0.1)
				(type default)
			)
			(layer "F.Fab")
		)
		(fp_line
			(start -0.12065 0.2794)
			(end -0.12065 0.3048)
			(stroke
				(width 0.1)
				(type default)
			)
			(layer "F.Fab")
		)
		(fp_line
			(start -0.12065 0.3048)
			(end -0.67945 0.3048)
			(stroke
				(width 0.1)
				(type default)
			)
			(layer "F.Fab")
		)
		(fp_line
			(start 0.120396 0.2794)
			(end -0.12065 0.2794)
			(stroke
				(width 0.1)
				(type default)
			)
			(layer "F.Fab")
		)
		(fp_line
			(start 0.120396 0.3048)
			(end 0.120396 0.2794)
			(stroke
				(width 0.1)
				(type default)
			)
			(layer "F.Fab")
		)
		(fp_line
			(start 0.12065 -0.3048)
			(end 0.67945 -0.3048)
			(stroke
				(width 0.1)
				(type default)
			)
			(layer "F.Fab")
		)
		(fp_line
			(start 0.12065 -0.2794)
			(end 0.12065 -0.3048)
			(stroke
				(width 0.1)
				(type default)
			)
			(layer "F.Fab")
		)
		(fp_line
			(start 0.67945 -0.3048)
			(end 0.67945 0.3048)
			(stroke
				(width 0.1)
				(type default)
			)
			(layer "F.Fab")
		)
		(fp_line
			(start 0.67945 0.3048)
			(end 0.120396 0.3048)
			(stroke
				(width 0.1)
				(type default)
			)
			(layer "F.Fab")
		)
		(pad "1" smd circle
			(at -0.40005 0)
			(size 0 0)
			(layers "F.Cu" "F.Mask" "F.Paste")
			(net "P3V3_STBY")
		)
		(pad "2" smd circle
			(at 0.40005 0)
			(size 0 0)
			(layers "F.Cu" "F.Mask" "F.Paste")
			(net "PWR_LED_R1")
		)
	)
	(footprint ""
		(layer "F.Cu")
		(at 35.941 -28.829)
		(property "Reference" "C9"
			(at 0.762 -6.83133 0)
			(unlocked yes)
			(layer "F.SilkS")
			(effects
				(font
					(size 0.7874 0.5842)
					(thickness 0.1524)
				)
				(justify left)
			)
		)
		(property "Value" ""
			(at 0 0 0)
			(layer "F.Fab")
			(effects
				(font
					(size 1.27 1.27)
				)
			)
		)
		(duplicate_pad_numbers_are_jumpers no)
		(fp_line
			(start -1.524 -0.762)
			(end 1.524 -0.762)
			(stroke
				(width 0.1524)
				(type default)
			)
			(layer "F.SilkS")
		)
		(fp_line
			(start -1.524 0.762)
			(end -1.524 -0.762)
			(stroke
				(width 0.1524)
				(type default)
			)
			(layer "F.SilkS")
		)
		(fp_line
			(start 1.524 -0.762)
			(end 1.524 0.762)
			(stroke
				(width 0.1524)
				(type default)
			)
			(layer "F.SilkS")
		)
		(fp_line
			(start 1.524 0.762)
			(end -1.524 0.762)
			(stroke
				(width 0.1524)
				(type default)
			)
			(layer "F.SilkS")
		)
		(fp_line
			(start -1.1049 -0.724916)
			(end -1.1049 0.724916)
			(stroke
				(width 0.1)
				(type default)
			)
			(layer "F.Fab")
		)
		(fp_line
			(start -1.1049 0.724916)
			(end 1.1049 0.724916)
			(stroke
				(width 0.1)
				(type default)
			)
			(layer "F.Fab")
		)
		(fp_line
			(start 1.1049 -0.724916)
			(end -1.1049 -0.724916)
			(stroke
				(width 0.1)
				(type default)
			)
			(layer "F.Fab")
		)
		(fp_line
			(start 1.1049 0.724916)
			(end 1.1049 -0.724916)
			(stroke
				(width 0.1)
				(type default)
			)
			(layer "F.Fab")
		)
		(pad "1" smd rect
			(at -0.889 0 180)
			(size 1.016 1.27)
			(layers "F.Cu" "F.Mask" "F.Paste")
			(net "P5V_STBY_DEBUG")
		)
		(pad "2" smd rect
			(at 0.889 0 180)
			(size 1.016 1.27)
			(layers "F.Cu" "F.Mask" "F.Paste")
			(net "GND")
		)
	)
	(footprint ""
		(layer "F.Cu")
		(at 3.937 -46.736 180)
		(property "Reference" "R61"
			(at 2.413 -0.15367 0)
			(unlocked yes)
			(layer "F.SilkS")
			(effects
				(font
					(size 0.7874 0.5842)
					(thickness 0.1524)
				)
			)
		)
		(property "Value" ""
			(at 0 0 180)
			(layer "F.Fab")
			(effects
				(font
					(size 1.27 1.27)
				)
			)
		)
		(duplicate_pad_numbers_are_jumpers no)
		(fp_line
			(start 0.7874 0.4064)
			(end -0.7874 0.4064)
			(stroke
				(width 0.1524)
				(type default)
			)
			(layer "F.SilkS")
		)
		(fp_line
			(start 0.7874 -0.4064)
			(end 0.7874 0.4064)
			(stroke
				(width 0.1524)
				(type default)
			)
			(layer "F.SilkS")
		)
		(fp_line
			(start -0.7874 0.4064)
			(end -0.7874 -0.4064)
			(stroke
				(width 0.1524)
				(type default)
			)
			(layer "F.SilkS")
		)
		(fp_line
			(start -0.7874 -0.4064)
			(end 0.7874 -0.4064)
			(stroke
				(width 0.1524)
				(type default)
			)
			(layer "F.SilkS")
		)
		(fp_line
			(start 0.67945 0.3048)
			(end 0.120396 0.3048)
			(stroke
				(width 0.1)
				(type default)
			)
			(layer "F.Fab")
		)
		(fp_line
			(start 0.67945 -0.3048)
			(end 0.67945 0.3048)
			(stroke
				(width 0.1)
				(type default)
			)
			(layer "F.Fab")
		)
		(fp_line
			(start 0.12065 -0.2794)
			(end 0.12065 -0.3048)
			(stroke
				(width 0.1)
				(type default)
			)
			(layer "F.Fab")
		)
		(fp_line
			(start 0.12065 -0.3048)
			(end 0.67945 -0.3048)
			(stroke
				(width 0.1)
				(type default)
			)
			(layer "F.Fab")
		)
		(fp_line
			(start 0.120396 0.3048)
			(end 0.120396 0.2794)
			(stroke
				(width 0.1)
				(type default)
			)
			(layer "F.Fab")
		)
		(fp_line
			(start 0.120396 0.2794)
			(end -0.12065 0.2794)
			(stroke
				(width 0.1)
				(type default)
			)
			(layer "F.Fab")
		)
		(fp_line
			(start -0.12065 0.3048)
			(end -0.67945 0.3048)
			(stroke
				(width 0.1)
				(type default)
			)
			(layer "F.Fab")
		)
		(fp_line
			(start -0.12065 0.2794)
			(end -0.12065 0.3048)
			(stroke
				(width 0.1)
				(type default)
			)
			(layer "F.Fab")
		)
		(fp_line
			(start -0.12065 -0.2794)
			(end 0.12065 -0.2794)
			(stroke
				(width 0.1)
				(type default)
			)
			(layer "F.Fab")
		)
		(fp_line
			(start -0.12065 -0.305054)
			(end -0.12065 -0.2794)
			(stroke
				(width 0.1)
				(type default)
			)
			(layer "F.Fab")
		)
		(fp_line
			(start -0.67945 0.3048)
			(end -0.67945 -0.305054)
			(stroke
				(width 0.1)
				(type default)
			)
			(layer "F.Fab")
		)
		(fp_line
			(start -0.67945 -0.305054)
			(end -0.12065 -0.305054)
			(stroke
				(width 0.1)
				(type default)
			)
			(layer "F.Fab")
		)
		(pad "1" smd circle
			(at -0.40005 0 180)
			(size 0 0)
			(layers "F.Cu" "F.Mask" "F.Paste")
			(net "PD_FRU_A2")
		)
		(pad "2" smd circle
			(at 0.40005 0 180)
			(size 0 0)
			(layers "F.Cu" "F.Mask" "F.Paste")
			(net "GND")
		)
	)
	(footprint ""
		(layer "F.Cu")
		(at 19.685 -63.373 90)
		(property "Reference" "R65"
			(at 0.762 -2.25933 90)
			(unlocked yes)
			(layer "F.SilkS")
			(effects
				(font
					(size 0.7874 0.5842)
					(thickness 0.1524)
				)
			)
		)
		(property "Value" ""
			(at 0 0 90)
			(layer "F.Fab")
			(effects
				(font
					(size 1.27 1.27)
				)
			)
		)
		(duplicate_pad_numbers_are_jumpers no)
		(fp_line
			(start 0.7874 -0.4064)
			(end 0.7874 0.4064)
			(stroke
				(width 0.1524)
				(type default)
			)
			(layer "F.SilkS")
		)
		(fp_line
			(start -0.7874 -0.4064)
			(end 0.7874 -0.4064)
			(stroke
				(width 0.1524)
				(type default)
			)
			(layer "F.SilkS")
		)
		(fp_line
			(start 0.7874 0.4064)
			(end -0.7874 0.4064)
			(stroke
				(width 0.1524)
				(type default)
			)
			(layer "F.SilkS")
		)
		(fp_line
			(start -0.7874 0.4064)
			(end -0.7874 -0.4064)
			(stroke
				(width 0.1524)
				(type default)
			)
			(layer "F.SilkS")
		)
		(fp_line
			(start -0.12065 -0.305054)
			(end -0.12065 -0.2794)
			(stroke
				(width 0.1)
				(type default)
			)
			(layer "F.Fab")
		)
		(fp_line
			(start -0.67945 -0.305054)
			(end -0.12065 -0.305054)
			(stroke
				(width 0.1)
				(type default)
			)
			(layer "F.Fab")
		)
		(fp_line
			(start 0.67945 -0.3048)
			(end 0.67945 0.3048)
			(stroke
				(width 0.1)
				(type default)
			)
			(layer "F.Fab")
		)
		(fp_line
			(start 0.12065 -0.3048)
			(end 0.67945 -0.3048)
			(stroke
				(width 0.1)
				(type default)
			)
			(layer "F.Fab")
		)
		(fp_line
			(start 0.12065 -0.2794)
			(end 0.12065 -0.3048)
			(stroke
				(width 0.1)
				(type default)
			)
			(layer "F.Fab")
		)
		(fp_line
			(start -0.12065 -0.2794)
			(end 0.12065 -0.2794)
			(stroke
				(width 0.1)
				(type default)
			)
			(layer "F.Fab")
		)
		(fp_line
			(start 0.120396 0.2794)
			(end -0.12065 0.2794)
			(stroke
				(width 0.1)
				(type default)
			)
			(layer "F.Fab")
		)
		(fp_line
			(start -0.12065 0.2794)
			(end -0.12065 0.3048)
			(stroke
				(width 0.1)
				(type default)
			)
			(layer "F.Fab")
		)
		(fp_line
			(start 0.67945 0.3048)
			(end 0.120396 0.3048)
			(stroke
				(width 0.1)
				(type default)
			)
			(layer "F.Fab")
		)
		(fp_line
			(start 0.120396 0.3048)
			(end 0.120396 0.2794)
			(stroke
				(width 0.1)
				(type default)
			)
			(layer "F.Fab")
		)
		(fp_line
			(start -0.12065 0.3048)
			(end -0.67945 0.3048)
			(stroke
				(width 0.1)
				(type default)
			)
			(layer "F.Fab")
		)
		(fp_line
			(start -0.67945 0.3048)
			(end -0.67945 -0.305054)
			(stroke
				(width 0.1)
				(type default)
			)
			(layer "F.Fab")
		)
		(pad "1" smd circle
			(at -0.40005 0 90)
			(size 0 0)
			(layers "F.Cu" "F.Mask" "F.Paste")
			(net "UART_DEBUG_R_TX")
		)
		(pad "2" smd circle
			(at 0.40005 0 90)
			(size 0 0)
			(layers "F.Cu" "F.Mask" "F.Paste")
			(net "UART_DEBUG_TX")
		)
	)
	(footprint ""
		(layer "F.Cu")
		(at 18.415 -57.785)
		(property "Reference" "R25"
			(at 3.81 0.02667 0)
			(unlocked yes)
			(layer "F.SilkS")
			(effects
				(font
					(size 0.7874 0.5842)
					(thickness 0.1524)
				)
			)
		)
		(property "Value" ""
			(at 0 0 0)
			(layer "F.Fab")
			(effects
				(font
					(size 1.27 1.27)
				)
			)
		)
		(duplicate_pad_numbers_are_jumpers no)
		(fp_line
			(start -0.7874 -0.4064)
			(end 0.7874 -0.4064)
			(stroke
				(width 0.1524)
				(type default)
			)
			(layer "F.SilkS")
		)
		(fp_line
			(start -0.7874 0.4064)
			(end -0.7874 -0.4064)
			(stroke
				(width 0.1524)
				(type default)
			)
			(layer "F.SilkS")
		)
		(fp_line
			(start 0.7874 -0.4064)
			(end 0.7874 0.4064)
			(stroke
				(width 0.1524)
				(type default)
			)
			(layer "F.SilkS")
		)
		(fp_line
			(start 0.7874 0.4064)
			(end -0.7874 0.4064)
			(stroke
				(width 0.1524)
				(type default)
			)
			(layer "F.SilkS")
		)
		(fp_line
			(start -0.67945 -0.305054)
			(end -0.12065 -0.305054)
			(stroke
				(width 0.1)
				(type default)
			)
			(layer "F.Fab")
		)
		(fp_line
			(start -0.67945 0.3048)
			(end -0.67945 -0.305054)
			(stroke
				(width 0.1)
				(type default)
			)
			(layer "F.Fab")
		)
		(fp_line
			(start -0.12065 -0.305054)
			(end -0.12065 -0.2794)
			(stroke
				(width 0.1)
				(type default)
			)
			(layer "F.Fab")
		)
		(fp_line
			(start -0.12065 -0.2794)
			(end 0.12065 -0.2794)
			(stroke
				(width 0.1)
				(type default)
			)
			(layer "F.Fab")
		)
		(fp_line
			(start -0.12065 0.2794)
			(end -0.12065 0.3048)
			(stroke
				(width 0.1)
				(type default)
			)
			(layer "F.Fab")
		)
		(fp_line
			(start -0.12065 0.3048)
			(end -0.67945 0.3048)
			(stroke
				(width 0.1)
				(type default)
			)
			(layer "F.Fab")
		)
		(fp_line
			(start 0.120396 0.2794)
			(end -0.12065 0.2794)
			(stroke
				(width 0.1)
				(type default)
			)
			(layer "F.Fab")
		)
		(fp_line
			(start 0.120396 0.3048)
			(end 0.120396 0.2794)
			(stroke
				(width 0.1)
				(type default)
			)
			(layer "F.Fab")
		)
		(fp_line
			(start 0.12065 -0.3048)
			(end 0.67945 -0.3048)
			(stroke
				(width 0.1)
				(type default)
			)
			(layer "F.Fab")
		)
		(fp_line
			(start 0.12065 -0.2794)
			(end 0.12065 -0.3048)
			(stroke
				(width 0.1)
				(type default)
			)
			(layer "F.Fab")
		)
		(fp_line
			(start 0.67945 -0.3048)
			(end 0.67945 0.3048)
			(stroke
				(width 0.1)
				(type default)
			)
			(layer "F.Fab")
		)
		(fp_line
			(start 0.67945 0.3048)
			(end 0.120396 0.3048)
			(stroke
				(width 0.1)
				(type default)
			)
			(layer "F.Fab")
		)
		(pad "1" smd circle
			(at -0.40005 0)
			(size 0 0)
			(layers "F.Cu" "F.Mask" "F.Paste")
			(net "PCA9539_A0")
		)
		(pad "2" smd circle
			(at 0.40005 0)
			(size 0 0)
			(layers "F.Cu" "F.Mask" "F.Paste")
			(net "GND")
		)
	)
)
